(kicad_pcb
	(version 20221018)
	(generator pcbnew)
	(general
    (thickness 1.518)
  )
	(paper "A4")
	(title_block
    (title "Kria K26 Devboard")
    (date "2024-03-26")
    (rev "1.2.5")
    (comment 1 "www.antmicro.com")
    (comment 2 "Antmicro Ltd.")
		(comment 9 "footprint 379 of 660 (J_SOM240_1), pads 103-205 of 242")
	)
	(layers
    (0 "F.Cu" mixed)
    (1 "In1.Cu" power)
    (2 "In2.Cu" mixed)
    (3 "In3.Cu" power)
    (4 "In4.Cu" mixed)
    (5 "In5.Cu" power)
    (6 "In6.Cu" mixed)
    (31 "B.Cu" power)
    (32 "B.Adhes" user "B.Adhesive")
    (33 "F.Adhes" user "F.Adhesive")
    (34 "B.Paste" user)
    (35 "F.Paste" user)
    (36 "B.SilkS" user "B.Silkscreen")
    (37 "F.SilkS" user "F.Silkscreen")
    (38 "B.Mask" user)
    (39 "F.Mask" user)
    (40 "Dwgs.User" user "User.Drawings")
    (41 "Cmts.User" user "User.Comments")
    (42 "Eco1.User" user "User.Eco1")
    (43 "Eco2.User" user "User.Eco2")
    (44 "Edge.Cuts" user)
    (45 "Margin" user)
    (46 "B.CrtYd" user "B.Courtyard")
    (47 "F.CrtYd" user "F.Courtyard")
    (48 "B.Fab" user)
    (49 "F.Fab" user)
  )
	(footprint "kria-k26-devboard-footprints:Conn_Plug_Samtec_ADM6_4x60_ADM6-60-01.5-L-4-2-A-TR"
    (layer "F.Cu")
    (at 91.5765 117.6215 -90)
    (property "Author" "Antmicro")
    (property "License" "Apache-2.0")
    (property "MPN" "ADM6-60-01.5-L-4-2-A-TR")
    (property "Manufacturer" "Samtec")
    (property "Sheetfile" "k26_som.kicad_sch")
    (property "Sheetname" "Xilinx K26 SOM")
    (property "ki_description" "Board to Board & Mezzanine Connectors 0.635 mm AcceleRate HD High-Density 4-Row Header 60P")
    (attr smd)
    (fp_text reference "J_SOM240_1" (at -13.8415 -3.7635 -90) (layer "F.SilkS")
        (effects (font (size 0.7 0.7) (thickness 0.15)) (justify left bottom))
    )
    (fp_text value "ADM6-60-01.5-L-4-2-A-TR" (at 0 3.7 -90) (layer "F.Fab") hide
        (effects (font (size 0.7 0.7) (thickness 0.15)) (justify left bottom))
    )
    (pad "B41" smd circle (at -6.668 -0.791 270) (size 0.356 0.356) (layers "F.Cu" "F.Paste" "F.Mask")
      (net 41 "/USB/MIO59") (pinfunction "B41") (pintype "passive"))
    (pad "B42" smd circle (at -7.303 -0.791 270) (size 0.356 0.356) (layers "F.Cu" "F.Paste" "F.Mask")
      (net 42 "/USB/MIO60") (pinfunction "B42") (pintype "passive"))
    (pad "B43" smd circle (at -7.938 -0.791 270) (size 0.356 0.356) (layers "F.Cu" "F.Paste" "F.Mask")
      (net 1 "GND") (pinfunction "B43") (pintype "passive"))
    (pad "B44" smd circle (at -8.573 -0.791 270) (size 0.356 0.356) (layers "F.Cu" "F.Paste" "F.Mask")
      (net 29 "/Ethernet/MIO70") (pinfunction "B44") (pintype "passive"))
    (pad "B45" smd circle (at -9.208 -0.791 270) (size 0.356 0.356) (layers "F.Cu" "F.Paste" "F.Mask")
      (net 30 "/Ethernet/MIO71") (pinfunction "B45") (pintype "passive"))
    (pad "B46" smd circle (at -9.843 -0.791 270) (size 0.356 0.356) (layers "F.Cu" "F.Paste" "F.Mask")
      (net 31 "/Ethernet/MIO72") (pinfunction "B46") (pintype "passive"))
    (pad "B47" smd circle (at -10.478 -0.791 270) (size 0.356 0.356) (layers "F.Cu" "F.Paste" "F.Mask")
      (net 1 "GND") (pinfunction "B47") (pintype "passive"))
    (pad "B48" smd circle (at -11.113 -0.791 270) (size 0.356 0.356) (layers "F.Cu" "F.Paste" "F.Mask")
      (net 1 "GND") (pinfunction "B48") (pintype "passive"))
    (pad "B49" smd circle (at -11.748 -0.791 270) (size 0.356 0.356) (layers "F.Cu" "F.Paste" "F.Mask")
      (net 179 "/Clock distribution/GTR_REFCLK1_C2M_P") (pinfunction "B49") (pintype "passive"))
    (pad "B50" smd circle (at -12.383 -0.791 270) (size 0.356 0.356) (layers "F.Cu" "F.Paste" "F.Mask")
      (net 180 "/Clock distribution/GTR_REFCLK1_C2M_N") (pinfunction "B50") (pintype "passive"))
    (pad "B51" smd circle (at -13.018 -0.791 270) (size 0.356 0.356) (layers "F.Cu" "F.Paste" "F.Mask")
      (net 1 "GND") (pinfunction "B51") (pintype "passive"))
    (pad "B52" smd circle (at -13.653 -0.791 270) (size 0.356 0.356) (layers "F.Cu" "F.Paste" "F.Mask")
      (net 1 "GND") (pinfunction "B52") (pintype "passive"))
    (pad "B53" smd circle (at -14.288 -0.791 270) (size 0.356 0.356) (layers "F.Cu" "F.Paste" "F.Mask")
      (net 56 "/USB/GTR_DP2_C2M_P") (pinfunction "B53") (pintype "passive"))
    (pad "B54" smd circle (at -14.923 -0.791 270) (size 0.356 0.356) (layers "F.Cu" "F.Paste" "F.Mask")
      (net 57 "/USB/GTR_DP2_C2M_N") (pinfunction "B54") (pintype "passive"))
    (pad "B55" smd circle (at -15.558 -0.791 270) (size 0.356 0.356) (layers "F.Cu" "F.Paste" "F.Mask")
      (net 1 "GND") (pinfunction "B55") (pintype "passive"))
    (pad "B56" smd circle (at -16.193 -0.791 270) (size 0.356 0.356) (layers "F.Cu" "F.Paste" "F.Mask")
      (net 1 "GND") (pinfunction "B56") (pintype "passive"))
    (pad "B57" smd circle (at -16.828 -0.791 270) (size 0.356 0.356) (layers "F.Cu" "F.Paste" "F.Mask")
      (net 100 "/Display Port/GTR_DP0_M2C_P") (pinfunction "B57") (pintype "passive"))
    (pad "B58" smd circle (at -17.463 -0.791 270) (size 0.356 0.356) (layers "F.Cu" "F.Paste" "F.Mask")
      (net 102 "/Display Port/GTR_DP0_M2C_N") (pinfunction "B58") (pintype "passive"))
    (pad "B59" smd circle (at -18.098 -0.791 270) (size 0.356 0.356) (layers "F.Cu" "F.Paste" "F.Mask")
      (net 1 "GND") (pinfunction "B59") (pintype "passive"))
    (pad "B60" smd circle (at -18.733 -0.791 270) (size 0.356 0.356) (layers "F.Cu" "F.Paste" "F.Mask")
      (net 8 "SOM_5V0") (pinfunction "B60") (pintype "passive"))
    (pad "C01" smd circle (at 18.732 0.79 270) (size 0.356 0.356) (layers "F.Cu" "F.Paste" "F.Mask")
      (net 1 "GND") (pinfunction "C01") (pintype "passive"))
    (pad "C02" smd circle (at 18.097 0.79 270) (size 0.356 0.356) (layers "F.Cu" "F.Paste" "F.Mask")
      (net 1 "GND") (pinfunction "C02") (pintype "passive"))
    (pad "C03" smd circle (at 17.462 0.79 270) (size 0.356 0.356) (layers "F.Cu" "F.Paste" "F.Mask")
      (net 210 "/Camera interface/HPA00_CC_P") (pinfunction "C03") (pintype "passive"))
    (pad "C04" smd circle (at 16.827 0.79 270) (size 0.356 0.356) (layers "F.Cu" "F.Paste" "F.Mask")
      (net 211 "/Camera interface/HPA00_CC_N") (pinfunction "C04") (pintype "passive"))
    (pad "C05" smd circle (at 16.192 0.79 270) (size 0.356 0.356) (layers "F.Cu" "F.Paste" "F.Mask")
      (net 1 "GND") (pinfunction "C05") (pintype "passive"))
    (pad "C06" smd circle (at 15.557 0.79 270) (size 0.356 0.356) (layers "F.Cu" "F.Paste" "F.Mask")
      (net 216 "/Camera interface/HPA03_P") (pinfunction "C06") (pintype "passive"))
    (pad "C07" smd circle (at 14.922 0.79 270) (size 0.356 0.356) (layers "F.Cu" "F.Paste" "F.Mask")
      (net 217 "/Camera interface/HPA03_N") (pinfunction "C07") (pintype "passive"))
    (pad "C08" smd circle (at 14.287 0.79 270) (size 0.356 0.356) (layers "F.Cu" "F.Paste" "F.Mask")
      (net 1 "GND") (pinfunction "C08") (pintype "passive"))
    (pad "C09" smd circle (at 13.652 0.79 270) (size 0.356 0.356) (layers "F.Cu" "F.Paste" "F.Mask")
      (net 206 "/Camera interface/HPA08_P") (pinfunction "C09") (pintype "passive"))
    (pad "C10" smd circle (at 13.017 0.79 270) (size 0.356 0.356) (layers "F.Cu" "F.Paste" "F.Mask")
      (net 207 "/Camera interface/HPA08_N") (pinfunction "C10") (pintype "passive"))
    (pad "C11" smd circle (at 12.382 0.79 270) (size 0.356 0.356) (layers "F.Cu" "F.Paste" "F.Mask")
      (net 1 "GND") (pinfunction "C11") (pintype "passive"))
    (pad "C12" smd circle (at 11.747 0.79 270) (size 0.356 0.356) (layers "F.Cu" "F.Paste" "F.Mask")
      (net 461 "/Xilinx K26 SOM/HPA10_CC_P") (pinfunction "C12") (pintype "passive"))
    (pad "C13" smd circle (at 11.112 0.79 270) (size 0.356 0.356) (layers "F.Cu" "F.Paste" "F.Mask")
      (net 462 "/Xilinx K26 SOM/HPA10_CC_N") (pinfunction "C13") (pintype "passive"))
    (pad "C14" smd circle (at 10.477 0.79 270) (size 0.356 0.356) (layers "F.Cu" "F.Paste" "F.Mask")
      (net 1 "GND") (pinfunction "C14") (pintype "passive"))
    (pad "C15" smd circle (at 9.842 0.79 270) (size 0.356 0.356) (layers "F.Cu" "F.Paste" "F.Mask")
      (net 151 "/Debug and JTAG/~{PS_POR}") (pinfunction "C15") (pintype "passive"))
    (pad "C16" smd circle (at 9.207 0.79 270) (size 0.356 0.356) (layers "F.Cu" "F.Paste" "F.Mask")
      (net 140 "/Debug and JTAG/~{PS_SRST_C2M}") (pinfunction "C16") (pintype "passive"))
    (pad "C17" smd circle (at 8.572 0.79 270) (size 0.356 0.356) (layers "F.Cu" "F.Paste" "F.Mask")
      (net 1 "GND") (pinfunction "C17") (pintype "passive"))
    (pad "C18" smd circle (at 7.937 0.79 270) (size 0.356 0.356) (layers "F.Cu" "F.Paste" "F.Mask")
      (net 463 "/Xilinx K26 SOM/HDA06") (pinfunction "C18") (pintype "passive"))
    (pad "C19" smd circle (at 7.302 0.79 270) (size 0.356 0.356) (layers "F.Cu" "F.Paste" "F.Mask")
      (net 464 "/Xilinx K26 SOM/HDA07") (pinfunction "C19") (pintype "passive"))
    (pad "C20" smd circle (at 6.667 0.79 270) (size 0.356 0.356) (layers "F.Cu" "F.Paste" "F.Mask")
      (net 465 "/Xilinx K26 SOM/HDA08_CC") (pinfunction "C20") (pintype "passive"))
    (pad "C21" smd circle (at 6.032 0.79 270) (size 0.356 0.356) (layers "F.Cu" "F.Paste" "F.Mask")
      (net 1 "GND") (pinfunction "C21") (pintype "passive"))
    (pad "C22" smd circle (at 5.397 0.79 270) (size 0.356 0.356) (layers "F.Cu" "F.Paste" "F.Mask")
      (net 152 "/PMOD/HDA18") (pinfunction "C22") (pintype "passive"))
    (pad "C23" smd circle (at 4.762 0.79 270) (size 0.356 0.356) (layers "F.Cu" "F.Paste" "F.Mask")
      (net 466 "/Xilinx K26 SOM/HDA19") (pinfunction "C23") (pintype "passive"))
    (pad "C24" smd circle (at 4.127 0.79 270) (size 0.356 0.356) (layers "F.Cu" "F.Paste" "F.Mask")
      (net 6 "/Xilinx K26 SOM/HDA20") (pinfunction "C24") (pintype "passive"))
    (pad "C25" smd circle (at 3.492 0.79 270) (size 0.356 0.356) (layers "F.Cu" "F.Paste" "F.Mask")
      (net 1 "GND") (pinfunction "C25") (pintype "passive"))
    (pad "C26" smd circle (at 2.857 0.79 270) (size 0.356 0.356) (layers "F.Cu" "F.Paste" "F.Mask")
      (net 153 "/I2C /MIO24_I2C_SCK") (pinfunction "C26") (pintype "passive"))
    (pad "C27" smd circle (at 2.222 0.79 270) (size 0.356 0.356) (layers "F.Cu" "F.Paste" "F.Mask")
      (net 432 "/I2C /MIO25_I2C_SDA") (pinfunction "C27") (pintype "passive"))
    (pad "C28" smd circle (at 1.587 0.79 270) (size 0.356 0.356) (layers "F.Cu" "F.Paste" "F.Mask")
      (net 467 "/Xilinx K26 SOM/MIO12_FWUEN_C2M_L") (pinfunction "C28") (pintype "passive"))
    (pad "C29" smd circle (at 0.952 0.79 270) (size 0.356 0.356) (layers "F.Cu" "F.Paste" "F.Mask")
      (net 1 "GND") (pinfunction "C29") (pintype "passive"))
    (pad "C30" smd circle (at 0.317 0.79 270) (size 0.356 0.356) (layers "F.Cu" "F.Paste" "F.Mask")
      (net 111 "/Display Port/MIO29") (pinfunction "C30") (pintype "passive"))
    (pad "C31" smd circle (at -0.318 0.79 270) (size 0.356 0.356) (layers "F.Cu" "F.Paste" "F.Mask")
      (net 112 "/Display Port/MIO30") (pinfunction "C31") (pintype "passive"))
    (pad "C32" smd circle (at -0.953 0.79 270) (size 0.356 0.356) (layers "F.Cu" "F.Paste" "F.Mask")
      (net 409 "/Xilinx K26 SOM/MIO31_SHUTDOWN") (pinfunction "C32") (pintype "passive"))
    (pad "C33" smd circle (at -1.588 0.79 270) (size 0.356 0.356) (layers "F.Cu" "F.Paste" "F.Mask")
      (net 1 "GND") (pinfunction "C33") (pintype "passive"))
    (pad "C34" smd circle (at -2.223 0.79 270) (size 0.356 0.356) (layers "F.Cu" "F.Paste" "F.Mask")
      (net 113 "/SD 3.0 card/MIO47") (pinfunction "C34") (pintype "passive"))
    (pad "C35" smd circle (at -2.858 0.79 270) (size 0.356 0.356) (layers "F.Cu" "F.Paste" "F.Mask")
      (net 114 "/SD 3.0 card/MIO48") (pinfunction "C35") (pintype "passive"))
    (pad "C36" smd circle (at -3.493 0.79 270) (size 0.356 0.356) (layers "F.Cu" "F.Paste" "F.Mask")
      (net 115 "/SD 3.0 card/MIO49") (pinfunction "C36") (pintype "passive"))
    (pad "C37" smd circle (at -4.128 0.79 270) (size 0.356 0.356) (layers "F.Cu" "F.Paste" "F.Mask")
      (net 1 "GND") (pinfunction "C37") (pintype "passive"))
    (pad "C38" smd circle (at -4.763 0.79 270) (size 0.356 0.356) (layers "F.Cu" "F.Paste" "F.Mask")
      (net 43 "/USB/MIO55") (pinfunction "C38") (pintype "passive"))
    (pad "C39" smd circle (at -5.398 0.79 270) (size 0.356 0.356) (layers "F.Cu" "F.Paste" "F.Mask")
      (net 44 "/USB/MIO56") (pinfunction "C39") (pintype "passive"))
    (pad "C40" smd circle (at -6.033 0.79 270) (size 0.356 0.356) (layers "F.Cu" "F.Paste" "F.Mask")
      (net 45 "/USB/MIO57") (pinfunction "C40") (pintype "passive"))
    (pad "C41" smd circle (at -6.668 0.79 270) (size 0.356 0.356) (layers "F.Cu" "F.Paste" "F.Mask")
      (net 1 "GND") (pinfunction "C41") (pintype "passive"))
    (pad "C42" smd circle (at -7.303 0.79 270) (size 0.356 0.356) (layers "F.Cu" "F.Paste" "F.Mask")
      (net 32 "/Ethernet/MIO67") (pinfunction "C42") (pintype "passive"))
    (pad "C43" smd circle (at -7.938 0.79 270) (size 0.356 0.356) (layers "F.Cu" "F.Paste" "F.Mask")
      (net 33 "/Ethernet/MIO68") (pinfunction "C43") (pintype "passive"))
    (pad "C44" smd circle (at -8.573 0.79 270) (size 0.356 0.356) (layers "F.Cu" "F.Paste" "F.Mask")
      (net 34 "/Ethernet/MIO69") (pinfunction "C44") (pintype "passive"))
    (pad "C45" smd circle (at -9.208 0.79 270) (size 0.356 0.356) (layers "F.Cu" "F.Paste" "F.Mask")
      (net 468 "unconnected-(J_SOM240_1-PadC45)") (pinfunction "C45") (pintype "passive+no_connect"))
    (pad "C46" smd circle (at -9.843 0.79 270) (size 0.356 0.356) (layers "F.Cu" "F.Paste" "F.Mask")
      (net 1 "GND") (pinfunction "C46") (pintype "passive"))
    (pad "C47" smd circle (at -10.478 0.79 270) (size 0.356 0.356) (layers "F.Cu" "F.Paste" "F.Mask")
      (net 181 "/Clock distribution/GTR_REFCLK0_C2M_P") (pinfunction "C47") (pintype "passive"))
    (pad "C48" smd circle (at -11.113 0.79 270) (size 0.356 0.356) (layers "F.Cu" "F.Paste" "F.Mask")
      (net 182 "/Clock distribution/GTR_REFCLK0_C2M_N") (pinfunction "C48") (pintype "passive"))
    (pad "C49" smd circle (at -11.748 0.79 270) (size 0.356 0.356) (layers "F.Cu" "F.Paste" "F.Mask")
      (net 1 "GND") (pinfunction "C49") (pintype "passive"))
    (pad "C50" smd circle (at -12.383 0.79 270) (size 0.356 0.356) (layers "F.Cu" "F.Paste" "F.Mask")
      (net 1 "GND") (pinfunction "C50") (pintype "passive"))
    (pad "C51" smd circle (at -13.018 0.79 270) (size 0.356 0.356) (layers "F.Cu" "F.Paste" "F.Mask")
      (net 88 "/PCIE M2 key E /GTR_DP3_M2C_P") (pinfunction "C51") (pintype "passive"))
    (pad "C52" smd circle (at -13.653 0.79 270) (size 0.356 0.356) (layers "F.Cu" "F.Paste" "F.Mask")
      (net 90 "/PCIE M2 key E /GTR_DP3_M2C_N") (pinfunction "C52") (pintype "passive"))
    (pad "C53" smd circle (at -14.288 0.79 270) (size 0.356 0.356) (layers "F.Cu" "F.Paste" "F.Mask")
      (net 1 "GND") (pinfunction "C53") (pintype "passive"))
    (pad "C54" smd circle (at -14.923 0.79 270) (size 0.356 0.356) (layers "F.Cu" "F.Paste" "F.Mask")
      (net 1 "GND") (pinfunction "C54") (pintype "passive"))
    (pad "C55" smd circle (at -15.558 0.79 270) (size 0.356 0.356) (layers "F.Cu" "F.Paste" "F.Mask")
      (net 469 "/Xilinx K26 SOM/GTR_DP1_C2M_P") (pinfunction "C55") (pintype "passive"))
    (pad "C56" smd circle (at -16.193 0.79 270) (size 0.356 0.356) (layers "F.Cu" "F.Paste" "F.Mask")
      (net 470 "/Xilinx K26 SOM/GTR_DP1_C2M_N") (pinfunction "C56") (pintype "passive"))
    (pad "C57" smd circle (at -16.828 0.79 270) (size 0.356 0.356) (layers "F.Cu" "F.Paste" "F.Mask")
      (net 1 "GND") (pinfunction "C57") (pintype "passive"))
    (pad "C58" smd circle (at -17.463 0.79 270) (size 0.356 0.356) (layers "F.Cu" "F.Paste" "F.Mask")
      (net 1 "GND") (pinfunction "C58") (pintype "passive"))
    (pad "C59" smd circle (at -18.098 0.79 270) (size 0.356 0.356) (layers "F.Cu" "F.Paste" "F.Mask")
      (net 8 "SOM_5V0") (pinfunction "C59") (pintype "passive"))
    (pad "C60" smd circle (at -18.733 0.79 270) (size 0.356 0.356) (layers "F.Cu" "F.Paste" "F.Mask")
      (net 8 "SOM_5V0") (pinfunction "C60") (pintype "passive"))
    (pad "D01" smd circle (at 18.732 1.749 270) (size 0.356 0.356) (layers "F.Cu" "F.Paste" "F.Mask")
      (net 21 "PL_1V2") (pinfunction "D01") (pintype "passive"))
    (pad "D02" smd circle (at 18.097 1.749 270) (size 0.356 0.356) (layers "F.Cu" "F.Paste" "F.Mask")
      (net 21 "PL_1V2") (pinfunction "D02") (pintype "passive"))
    (pad "D03" smd circle (at 17.462 1.749 270) (size 0.356 0.356) (layers "F.Cu" "F.Paste" "F.Mask")
      (net 1 "GND") (pinfunction "D03") (pintype "passive"))
    (pad "D04" smd circle (at 16.827 1.749 270) (size 0.356 0.356) (layers "F.Cu" "F.Paste" "F.Mask")
      (net 214 "/Camera interface/HPA02_P") (pinfunction "D04") (pintype "passive"))
    (pad "D05" smd circle (at 16.192 1.749 270) (size 0.356 0.356) (layers "F.Cu" "F.Paste" "F.Mask")
      (net 215 "/Camera interface/HPA02_N") (pinfunction "D05") (pintype "passive"))
    (pad "D06" smd circle (at 15.557 1.749 270) (size 0.356 0.356) (layers "F.Cu" "F.Paste" "F.Mask")
      (net 1 "GND") (pinfunction "D06") (pintype "passive"))
    (pad "D07" smd circle (at 14.922 1.749 270) (size 0.356 0.356) (layers "F.Cu" "F.Paste" "F.Mask")
      (net 212 "/Camera interface/HPA01_P") (pinfunction "D07") (pintype "passive"))
    (pad "D08" smd circle (at 14.287 1.749 270) (size 0.356 0.356) (layers "F.Cu" "F.Paste" "F.Mask")
      (net 213 "/Camera interface/HPA01_N") (pinfunction "D08") (pintype "passive"))
    (pad "D09" smd circle (at 13.652 1.749 270) (size 0.356 0.356) (layers "F.Cu" "F.Paste" "F.Mask")
      (net 1 "GND") (pinfunction "D09") (pintype "passive"))
    (pad "D10" smd circle (at 13.017 1.749 270) (size 0.356 0.356) (layers "F.Cu" "F.Paste" "F.Mask")
      (net 208 "/Camera interface/HPA09_P") (pinfunction "D10") (pintype "passive"))
    (pad "D11" smd circle (at 12.382 1.749 270) (size 0.356 0.356) (layers "F.Cu" "F.Paste" "F.Mask")
      (net 209 "/Camera interface/HPA09_N") (pinfunction "D11") (pintype "passive"))
    (pad "D12" smd circle (at 11.747 1.749 270) (size 0.356 0.356) (layers "F.Cu" "F.Paste" "F.Mask")
      (net 1 "GND") (pinfunction "D12") (pintype "passive"))
    (pad "D13" smd circle (at 11.112 1.749 270) (size 0.356 0.356) (layers "F.Cu" "F.Paste" "F.Mask")
      (net 471 "/Xilinx K26 SOM/HPA14_P") (pinfunction "D13") (pintype "passive"))
    (pad "D14" smd circle (at 10.477 1.749 270) (size 0.356 0.356) (layers "F.Cu" "F.Paste" "F.Mask")
      (net 472 "/Xilinx K26 SOM/HPA14_N") (pinfunction "D14") (pintype "passive"))
    (pad "D15" smd circle (at 9.842 1.749 270) (size 0.356 0.356) (layers "F.Cu" "F.Paste" "F.Mask")
      (net 1 "GND") (pinfunction "D15") (pintype "passive"))
    (pad "D16" smd circle (at 9.207 1.749 270) (size 0.356 0.356) (layers "F.Cu" "F.Paste" "F.Mask")
      (net 410 "/Camera interface/HDA00_CC") (pinfunction "D16") (pintype "passive"))
    (pad "D17" smd circle (at 8.572 1.749 270) (size 0.356 0.356) (layers "F.Cu" "F.Paste" "F.Mask")
      (net 225 "/Camera interface/HDA01") (pinfunction "D17") (pintype "passive"))
    (pad "D18" smd circle (at 7.937 1.749 270) (size 0.356 0.356) (layers "F.Cu" "F.Paste" "F.Mask")
      (net 129 "/Reset logic/HDA02") (pinfunction "D18") (pintype "passive"))
    (pad "D19" smd circle (at 7.302 1.749 270) (size 0.356 0.356) (layers "F.Cu" "F.Paste" "F.Mask")
      (net 1 "GND") (pinfunction "D19") (pintype "passive"))
    (pad "D20" smd circle (at 6.667 1.749 270) (size 0.356 0.356) (layers "F.Cu" "F.Paste" "F.Mask")
      (net 155 "/PMOD/HDA12") (pinfunction "D20") (pintype "passive"))
    (pad "D21" smd circle (at 6.032 1.749 270) (size 0.356 0.356) (layers "F.Cu" "F.Paste" "F.Mask")
      (net 156 "/PMOD/HDA13") (pinfunction "D21") (pintype "passive"))
    (pad "D22" smd circle (at 5.397 1.749 270) (size 0.356 0.356) (layers "F.Cu" "F.Paste" "F.Mask")
      (net 157 "/PMOD/HDA14") (pinfunction "D22") (pintype "passive"))
    (pad "D23" smd circle (at 4.762 1.749 270) (size 0.356 0.356) (layers "F.Cu" "F.Paste" "F.Mask")
      (net 1 "GND") (pinfunction "D23") (pintype "passive"))
  )
)
